(kicad_pcb
	(version 20260206)
	(generator "pcbnew")
	(generator_version "10.0")
	(general
		(thickness 1.6)
		(legacy_teardrops no)
	)
	(paper "A4")
	(title_block
		(title "Bryce Canyon_SCC_16316-1_OCP.brd")
		(comment 1 "Bryce Canyon / footprints 1497-1504 of 1561")
	)
	(layers
		(0 "F.Cu" signal "TOP")
		(4 "In1.Cu" signal "L2GND")
		(6 "In2.Cu" signal "L3")
		(8 "In3.Cu" signal "L4VCC")
		(10 "In4.Cu" signal "L5VCC")
		(12 "In5.Cu" signal "L6")
		(14 "In6.Cu" signal "L7GND")
		(2 "B.Cu" signal "BOTTOM")
		(9 "F.Adhes" user "F.Adhesive")
		(11 "B.Adhes" user "B.Adhesive")
		(13 "F.Paste" user "Package Geometry/Pastemask Top")
		(15 "B.Paste" user "Package Geometry/Pastemask Bottom")
		(5 "F.SilkS" user "Ref Des/Silkscreen Top")
		(7 "B.SilkS" user "Ref Des/Silkscreen Bottom")
		(1 "F.Mask" user "Board Geometry/Soldermask Top")
		(3 "B.Mask" user "Board Geometry/Soldermask Bottom")
		(17 "Dwgs.User" user "User.Drawings")
		(19 "Cmts.User" user "User.Comments")
		(21 "Eco1.User" user "User.Eco1")
		(23 "Eco2.User" user "User.Eco2")
		(25 "Edge.Cuts" user "Board Geometry/Outline")
		(27 "Margin" user)
		(31 "F.CrtYd" user "Package Geometry/Place Bound Top")
		(29 "B.CrtYd" user "Package Geometry/Place Bound Bottom")
		(35 "F.Fab" user "Ref Des/Assembly Top")
		(33 "B.Fab" user "Ref Des/Assembly Bottom")
	)
	(footprint ""
		(layer "B.Cu")
		(at 163.892992 -11.70813)
		(property "Reference" "C104"
			(at 0 0 0)
			(layer "B.SilkS")
			(hide yes)
			(effects
				(font
					(size 1.27 1.27)
				)
				(justify mirror)
			)
		)
		(property "Value" "SCD1U16V2KX-3GP"
			(at -1.1811 -2.7051 0)
			(unlocked yes)
			(layer "B.Fab")
			(hide yes)
			(effects
				(font
					(size 1.016 1.016)
					(thickness 0.1524)
				)
				(justify mirror)
			)
		)
		(property "Device Type" "C402H22"
			(at -1.1811 -4.2291 0)
			(unlocked yes)
			(layer "B.Fab")
			(hide yes)
			(effects
				(font
					(size 1.016 1.016)
					(thickness 0.1524)
				)
				(justify mirror)
			)
		)
		(duplicate_pad_numbers_are_jumpers no)
		(fp_rect
			(start 0.4318 0.9525)
			(end -0.4318 -0.9525)
			(stroke
				(width 0)
				(type default)
			)
			(fill no)
			(layer "B.CrtYd")
		)
		(fp_rect
			(start 0.4318 0.9525)
			(end -0.4318 -0.9525)
			(stroke
				(width 0)
				(type default)
			)
			(fill no)
			(layer "B.Fab")
		)
		(pad "1" smd custom
			(at 0 -0.4445 180)
			(size 0.1524 0.1524)
			(layers "B.Cu" "B.Mask" "B.Paste")
			(net "P3V3")
			(options
				(clearance outline)
				(anchor circle)
			)
			(primitives
				(gr_poly
					(pts
						(arc
							(start 0.3048 0.2032)
							(mid 0.275042 0.275042)
							(end 0.2032 0.3048)
						)
						(arc
							(start -0.2032 0.3048)
							(mid -0.275042 0.275042)
							(end -0.3048 0.2032)
						)
						(arc
							(start -0.3048 -0.2032)
							(mid -0.275042 -0.275042)
							(end -0.2032 -0.3048)
						)
						(arc
							(start 0.2032 -0.3048)
							(mid 0.275042 -0.275042)
							(end 0.3048 -0.2032)
						)
					)
					(width 0)
					(fill yes)
				)
			)
		)
		(pad "2" smd custom
			(at 0 0.4445 180)
			(size 0.1524 0.1524)
			(layers "B.Cu" "B.Mask" "B.Paste")
			(net "GND")
			(options
				(clearance outline)
				(anchor circle)
			)
			(primitives
				(gr_poly
					(pts
						(arc
							(start 0.3048 0.2032)
							(mid 0.275042 0.275042)
							(end 0.2032 0.3048)
						)
						(arc
							(start -0.2032 0.3048)
							(mid -0.275042 0.275042)
							(end -0.3048 0.2032)
						)
						(arc
							(start -0.3048 -0.2032)
							(mid -0.275042 -0.275042)
							(end -0.2032 -0.3048)
						)
						(arc
							(start 0.2032 -0.3048)
							(mid 0.275042 -0.275042)
							(end 0.3048 -0.2032)
						)
					)
					(width 0)
					(fill yes)
				)
			)
		)
	)
	(footprint ""
		(layer "B.Cu")
		(at 118.756938 -66.3575)
		(property "Reference" "C185"
			(at 0 0 0)
			(layer "B.SilkS")
			(hide yes)
			(effects
				(font
					(size 1.27 1.27)
				)
				(justify mirror)
			)
		)
		(property "Value" "SC10U6D3V2MX-GP-U"
			(at 1.524 -1.905 0)
			(unlocked yes)
			(layer "B.Fab")
			(hide yes)
			(effects
				(font
					(size 1.016 1.016)
					(thickness 0.1524)
				)
				(justify mirror)
			)
		)
		(property "Device Type" "C402-TO0D2H28"
			(at 1.524 -3.429 0)
			(unlocked yes)
			(layer "B.Fab")
			(hide yes)
			(effects
				(font
					(size 1.016 1.016)
					(thickness 0.1524)
				)
				(justify mirror)
			)
		)
		(duplicate_pad_numbers_are_jumpers no)
		(fp_rect
			(start 0.4826 0.889)
			(end -0.4826 -0.889)
			(stroke
				(width 0)
				(type default)
			)
			(fill no)
			(layer "B.CrtYd")
		)
		(fp_rect
			(start 0.4826 0.889)
			(end -0.4826 -0.889)
			(stroke
				(width 0)
				(type default)
			)
			(fill no)
			(layer "B.Fab")
		)
		(pad "1" smd custom
			(at 0 -0.4572 180)
			(size 0.1524 0.1524)
			(layers "B.Cu" "B.Mask" "B.Paste")
			(net "P0V9")
			(options
				(clearance outline)
				(anchor circle)
			)
			(primitives
				(gr_poly
					(pts
						(arc
							(start -0.254 -0.3048)
							(mid -0.325842 -0.275042)
							(end -0.3556 -0.2032)
						)
						(arc
							(start -0.3556 0.2032)
							(mid -0.325842 0.275042)
							(end -0.254 0.3048)
						)
						(arc
							(start 0.254 0.3048)
							(mid 0.325842 0.275042)
							(end 0.3556 0.2032)
						)
						(arc
							(start 0.3556 -0.2032)
							(mid 0.325842 -0.275042)
							(end 0.254 -0.3048)
						)
					)
					(width 0)
					(fill yes)
				)
			)
		)
		(pad "2" smd custom
			(at 0 0.4572 180)
			(size 0.1524 0.1524)
			(layers "B.Cu" "B.Mask" "B.Paste")
			(net "GND")
			(options
				(clearance outline)
				(anchor circle)
			)
			(primitives
				(gr_poly
					(pts
						(arc
							(start -0.254 -0.3048)
							(mid -0.325842 -0.275042)
							(end -0.3556 -0.2032)
						)
						(arc
							(start -0.3556 0.2032)
							(mid -0.325842 0.275042)
							(end -0.254 0.3048)
						)
						(arc
							(start 0.254 0.3048)
							(mid 0.325842 0.275042)
							(end 0.3556 0.2032)
						)
						(arc
							(start 0.3556 -0.2032)
							(mid 0.325842 -0.275042)
							(end 0.254 -0.3048)
						)
					)
					(width 0)
					(fill yes)
				)
			)
		)
	)
	(footprint ""
		(layer "B.Cu")
		(at 113.2586 -57.4802)
		(property "Reference" "C538"
			(at 0 0 0)
			(layer "B.SilkS")
			(hide yes)
			(effects
				(font
					(size 1.27 1.27)
				)
				(justify mirror)
			)
		)
		(property "Value" "SCD1U6D3V1KX-GP"
			(at 2.8321 -1.7399 0)
			(unlocked yes)
			(layer "B.Fab")
			(hide yes)
			(effects
				(font
					(size 1.016 1.016)
					(thickness 0.1524)
				)
				(justify mirror)
			)
		)
		(property "Device Type" "C0201H13"
			(at 2.8321 -3.2639 0)
			(unlocked yes)
			(layer "B.Fab")
			(hide yes)
			(effects
				(font
					(size 1.016 1.016)
					(thickness 0.1524)
				)
				(justify mirror)
			)
		)
		(duplicate_pad_numbers_are_jumpers no)
		(fp_rect
			(start 0.2794 0.6477)
			(end -0.2794 -0.6477)
			(stroke
				(width 0)
				(type default)
			)
			(fill no)
			(layer "B.CrtYd")
		)
		(fp_rect
			(start 0.2794 0.6477)
			(end -0.2794 -0.6477)
			(stroke
				(width 0)
				(type default)
			)
			(fill no)
			(layer "B.Fab")
		)
		(pad "1" smd custom
			(at 0 -0.2794 180)
			(size 0.0762 0.0762)
			(layers "B.Cu" "B.Mask" "B.Paste")
			(net "GB_VDDA")
			(options
				(clearance outline)
				(anchor circle)
			)
			(primitives
				(gr_poly
					(pts
						(arc
							(start 0.1524 0.127)
							(mid 0.137521 0.162921)
							(end 0.1016 0.1778)
						)
						(arc
							(start -0.1016 0.1778)
							(mid -0.137521 0.162921)
							(end -0.1524 0.127)
						)
						(arc
							(start -0.1524 -0.127)
							(mid -0.137521 -0.162921)
							(end -0.1016 -0.1778)
						)
						(arc
							(start 0.1016 -0.1778)
							(mid 0.137521 -0.162921)
							(end 0.1524 -0.127)
						)
					)
					(width 0)
					(fill yes)
				)
			)
		)
		(pad "2" smd custom
			(at 0 0.2794 180)
			(size 0.0762 0.0762)
			(layers "B.Cu" "B.Mask" "B.Paste")
			(net "GND")
			(options
				(clearance outline)
				(anchor circle)
			)
			(primitives
				(gr_poly
					(pts
						(arc
							(start 0.1524 0.127)
							(mid 0.137521 0.162921)
							(end 0.1016 0.1778)
						)
						(arc
							(start -0.1016 0.1778)
							(mid -0.137521 0.162921)
							(end -0.1524 0.127)
						)
						(arc
							(start -0.1524 -0.127)
							(mid -0.137521 -0.162921)
							(end -0.1016 -0.1778)
						)
						(arc
							(start 0.1016 -0.1778)
							(mid 0.137521 -0.162921)
							(end 0.1524 -0.127)
						)
					)
					(width 0)
					(fill yes)
				)
			)
		)
	)
	(footprint ""
		(layer "B.Cu")
		(at 122.584972 -86.650068 180)
		(property "Reference" "R78"
			(at 0 0 0)
			(layer "B.SilkS")
			(hide yes)
			(effects
				(font
					(size 1.27 1.27)
				)
				(justify mirror)
			)
		)
		(property "Value" "4K7R2F-GP"
			(at -0.064008 -3.993896 180)
			(unlocked yes)
			(layer "B.Fab")
			(hide yes)
			(effects
				(font
					(size 1.016 1.016)
					(thickness 0.1524)
				)
				(justify mirror)
			)
		)
		(property "Device Type" "R402H16"
			(at -0.064008 -5.517896 180)
			(unlocked yes)
			(layer "B.Fab")
			(hide yes)
			(effects
				(font
					(size 1.016 1.016)
					(thickness 0.1524)
				)
				(justify mirror)
			)
		)
		(duplicate_pad_numbers_are_jumpers no)
		(fp_line
			(start 0.508 -0.9398)
			(end 0.508 0.9398)
			(stroke
				(width 0.1524)
				(type default)
			)
			(layer "B.SilkS")
		)
		(fp_line
			(start -0.508 -0.9398)
			(end 0.508 -0.9398)
			(stroke
				(width 0.1524)
				(type default)
			)
			(layer "B.SilkS")
		)
		(fp_rect
			(start 0.508 0.9398)
			(end -0.508 -0.9398)
			(stroke
				(width 0)
				(type default)
			)
			(fill no)
			(layer "B.CrtYd")
		)
		(fp_rect
			(start 0.508 0.9398)
			(end -0.508 -0.9398)
			(stroke
				(width 0)
				(type default)
			)
			(fill no)
			(layer "B.Fab")
		)
		(pad "1" smd custom
			(at 0 -0.4445)
			(size 0.1397 0.1397)
			(layers "B.Cu" "B.Mask" "B.Paste")
			(net "SCC_TYPE_2_LS")
			(options
				(clearance outline)
				(anchor circle)
			)
			(primitives
				(gr_poly
					(pts
						(arc
							(start -0.1778 0.2794)
							(mid -0.249642 0.249642)
							(end -0.2794 0.1778)
						)
						(arc
							(start -0.2794 -0.1778)
							(mid -0.249642 -0.249642)
							(end -0.1778 -0.2794)
						)
						(arc
							(start 0.1778 -0.2794)
							(mid 0.249642 -0.249642)
							(end 0.2794 -0.1778)
						)
						(arc
							(start 0.2794 0.1778)
							(mid 0.249642 0.249642)
							(end 0.1778 0.2794)
						)
					)
					(width 0)
					(fill yes)
				)
			)
		)
		(pad "2" smd custom
			(at 0 0.4445)
			(size 0.1397 0.1397)
			(layers "B.Cu" "B.Mask" "B.Paste")
			(net "GND")
			(options
				(clearance outline)
				(anchor circle)
			)
			(primitives
				(gr_poly
					(pts
						(arc
							(start -0.1778 0.2794)
							(mid -0.249642 0.249642)
							(end -0.2794 0.1778)
						)
						(arc
							(start -0.2794 -0.1778)
							(mid -0.249642 -0.249642)
							(end -0.1778 -0.2794)
						)
						(arc
							(start 0.1778 -0.2794)
							(mid 0.249642 -0.249642)
							(end 0.2794 -0.1778)
						)
						(arc
							(start 0.2794 0.1778)
							(mid 0.249642 0.249642)
							(end 0.1778 0.2794)
						)
					)
					(width 0)
					(fill yes)
				)
			)
		)
	)
	(footprint ""
		(layer "B.Cu")
		(at 164.085016 -45.661072)
		(property "Reference" "TP90"
			(at 0 0 0)
			(layer "B.SilkS")
			(hide yes)
			(effects
				(font
					(size 1.27 1.27)
				)
				(justify mirror)
			)
		)
		(property "Value" "TPAD28-2-GP"
			(at 0.0127 -1.6637 0)
			(unlocked yes)
			(layer "B.Fab")
			(hide yes)
			(effects
				(font
					(size 1.016 1.016)
					(thickness 0.1524)
				)
				(justify mirror)
			)
		)
		(property "Device Type" "TPAD28"
			(at 0.0127 -3.1877 0)
			(unlocked yes)
			(layer "B.Fab")
			(hide yes)
			(effects
				(font
					(size 1.016 1.016)
					(thickness 0.1524)
				)
				(justify mirror)
			)
		)
		(duplicate_pad_numbers_are_jumpers no)
		(fp_poly
			(pts
				(arc
					(start 0.3556 0)
					(mid -0.3556 0)
					(end 0.3556 0)
				)
			)
			(stroke
				(width 0)
				(type default)
			)
			(fill no)
			(layer "B.CrtYd")
		)
		(fp_poly
			(pts
				(arc
					(start 0.6096 0)
					(mid -0.6096 0)
					(end 0.6096 0)
				)
			)
			(stroke
				(width 0)
				(type default)
			)
			(fill no)
			(layer "B.Fab")
		)
		(pad "1" smd circle
			(at 0 0 180)
			(size 0.7112 0.7112)
			(layers "B.Cu" "B.Mask" "B.Paste")
			(net "SIO_DIN_1")
		)
	)
	(footprint ""
		(layer "B.Cu")
		(at 176.193196 -33.60293)
		(property "Reference" "TP147"
			(at 0 0 0)
			(layer "B.SilkS")
			(hide yes)
			(effects
				(font
					(size 1.27 1.27)
				)
				(justify mirror)
			)
		)
		(property "Value" "TPAD28-2-GP"
			(at 0.0127 -1.6637 0)
			(unlocked yes)
			(layer "B.Fab")
			(hide yes)
			(effects
				(font
					(size 1.016 1.016)
					(thickness 0.1524)
				)
				(justify mirror)
			)
		)
		(property "Device Type" "TPAD28"
			(at 0.0127 -3.1877 0)
			(unlocked yes)
			(layer "B.Fab")
			(hide yes)
			(effects
				(font
					(size 1.016 1.016)
					(thickness 0.1524)
				)
				(justify mirror)
			)
		)
		(duplicate_pad_numbers_are_jumpers no)
		(fp_poly
			(pts
				(arc
					(start 0.3556 0)
					(mid -0.3556 0)
					(end 0.3556 0)
				)
			)
			(stroke
				(width 0)
				(type default)
			)
			(fill no)
			(layer "B.CrtYd")
		)
		(fp_poly
			(pts
				(arc
					(start 0.6096 0)
					(mid -0.6096 0)
					(end 0.6096 0)
				)
			)
			(stroke
				(width 0)
				(type default)
			)
			(fill no)
			(layer "B.Fab")
		)
		(pad "1" smd circle
			(at 0 0 180)
			(size 0.7112 0.7112)
			(layers "B.Cu" "B.Mask" "B.Paste")
			(net "SPARE3")
		)
	)
	(footprint ""
		(layer "B.Cu")
		(at 172.844206 -68.199 90)
		(property "Reference" "R317"
			(at 0 0 90)
			(layer "B.SilkS")
			(hide yes)
			(effects
				(font
					(size 1.27 1.27)
				)
				(justify mirror)
			)
		)
		(property "Value" "4K7R2F-GP"
			(at -0.064008 -3.993896 90)
			(unlocked yes)
			(layer "B.Fab")
			(hide yes)
			(effects
				(font
					(size 1.016 1.016)
					(thickness 0.1524)
				)
				(justify mirror)
			)
		)
		(property "Device Type" "R402H16"
			(at -0.064008 -5.517896 90)
			(unlocked yes)
			(layer "B.Fab")
			(hide yes)
			(effects
				(font
					(size 1.016 1.016)
					(thickness 0.1524)
				)
				(justify mirror)
			)
		)
		(duplicate_pad_numbers_are_jumpers no)
		(fp_line
			(start 0.508 -0.9398)
			(end 0.508 0.9398)
			(stroke
				(width 0.1524)
				(type default)
			)
			(layer "B.SilkS")
		)
		(fp_line
			(start -0.508 -0.9398)
			(end 0.508 -0.9398)
			(stroke
				(width 0.1524)
				(type default)
			)
			(layer "B.SilkS")
		)
		(fp_rect
			(start 0.508 0.9398)
			(end -0.508 -0.9398)
			(stroke
				(width 0)
				(type default)
			)
			(fill no)
			(layer "B.CrtYd")
		)
		(fp_rect
			(start 0.508 0.9398)
			(end -0.508 -0.9398)
			(stroke
				(width 0)
				(type default)
			)
			(fill no)
			(layer "B.Fab")
		)
		(pad "1" smd custom
			(at 0 -0.4445 270)
			(size 0.1397 0.1397)
			(layers "B.Cu" "B.Mask" "B.Paste")
			(net "P3V3")
			(options
				(clearance outline)
				(anchor circle)
			)
			(primitives
				(gr_poly
					(pts
						(arc
							(start -0.1778 0.2794)
							(mid -0.249642 0.249642)
							(end -0.2794 0.1778)
						)
						(arc
							(start -0.2794 -0.1778)
							(mid -0.249642 -0.249642)
							(end -0.1778 -0.2794)
						)
						(arc
							(start 0.1778 -0.2794)
							(mid 0.249642 -0.249642)
							(end 0.2794 -0.1778)
						)
						(arc
							(start 0.2794 0.1778)
							(mid 0.249642 0.249642)
							(end 0.1778 0.2794)
						)
					)
					(width 0)
					(fill yes)
				)
			)
		)
		(pad "2" smd custom
			(at 0 0.4445 270)
			(size 0.1397 0.1397)
			(layers "B.Cu" "B.Mask" "B.Paste")
			(net "SYS_RST_Q8")
			(options
				(clearance outline)
				(anchor circle)
			)
			(primitives
				(gr_poly
					(pts
						(arc
							(start -0.1778 0.2794)
							(mid -0.249642 0.249642)
							(end -0.2794 0.1778)
						)
						(arc
							(start -0.2794 -0.1778)
							(mid -0.249642 -0.249642)
							(end -0.1778 -0.2794)
						)
						(arc
							(start 0.1778 -0.2794)
							(mid 0.249642 -0.249642)
							(end 0.2794 -0.1778)
						)
						(arc
							(start 0.2794 0.1778)
							(mid 0.249642 0.249642)
							(end 0.1778 0.2794)
						)
					)
					(width 0)
					(fill yes)
				)
			)
		)
	)
	(footprint ""
		(layer "B.Cu")
		(at 110.744 -59.4487)
		(property "Reference" "C240"
			(at 0 0 0)
			(layer "B.SilkS")
			(hide yes)
			(effects
				(font
					(size 1.27 1.27)
				)
				(justify mirror)
			)
		)
		(property "Value" "SCD1U6D3V1KX-GP"
			(at 2.8321 -1.7399 0)
			(unlocked yes)
			(layer "B.Fab")
			(hide yes)
			(effects
				(font
					(size 1.016 1.016)
					(thickness 0.1524)
				)
				(justify mirror)
			)
		)
		(property "Device Type" "C0201H13"
			(at 2.8321 -3.2639 0)
			(unlocked yes)
			(layer "B.Fab")
			(hide yes)
			(effects
				(font
					(size 1.016 1.016)
					(thickness 0.1524)
				)
				(justify mirror)
			)
		)
		(duplicate_pad_numbers_are_jumpers no)
		(fp_rect
			(start 0.2794 0.6477)
			(end -0.2794 -0.6477)
			(stroke
				(width 0)
				(type default)
			)
			(fill no)
			(layer "B.CrtYd")
		)
		(fp_rect
			(start 0.2794 0.6477)
			(end -0.2794 -0.6477)
			(stroke
				(width 0)
				(type default)
			)
			(fill no)
			(layer "B.Fab")
		)
		(pad "1" smd custom
			(at 0 -0.2794 180)
			(size 0.0762 0.0762)
			(layers "B.Cu" "B.Mask" "B.Paste")
			(net "GB_VDDA")
			(options
				(clearance outline)
				(anchor circle)
			)
			(primitives
				(gr_poly
					(pts
						(arc
							(start 0.1524 0.127)
							(mid 0.137521 0.162921)
							(end 0.1016 0.1778)
						)
						(arc
							(start -0.1016 0.1778)
							(mid -0.137521 0.162921)
							(end -0.1524 0.127)
						)
						(arc
							(start -0.1524 -0.127)
							(mid -0.137521 -0.162921)
							(end -0.1016 -0.1778)
						)
						(arc
							(start 0.1016 -0.1778)
							(mid 0.137521 -0.162921)
							(end 0.1524 -0.127)
						)
					)
					(width 0)
					(fill yes)
				)
			)
		)
		(pad "2" smd custom
			(at 0 0.2794 180)
			(size 0.0762 0.0762)
			(layers "B.Cu" "B.Mask" "B.Paste")
			(net "GND")
			(options
				(clearance outline)
				(anchor circle)
			)
			(primitives
				(gr_poly
					(pts
						(arc
							(start 0.1524 0.127)
							(mid 0.137521 0.162921)
							(end 0.1016 0.1778)
						)
						(arc
							(start -0.1016 0.1778)
							(mid -0.137521 0.162921)
							(end -0.1524 0.127)
						)
						(arc
							(start -0.1524 -0.127)
							(mid -0.137521 -0.162921)
							(end -0.1016 -0.1778)
						)
						(arc
							(start 0.1016 -0.1778)
							(mid 0.137521 -0.162921)
							(end 0.1524 -0.127)
						)
					)
					(width 0)
					(fill yes)
				)
			)
		)
	)
)
